(kicad_pcb
	(version 20260206)
	(generator "pcbnew")
	(generator_version "10.0")
	(general
		(thickness 1.6)
		(legacy_teardrops no)
	)
	(paper "A4")
	(title_block
		(title "04192023_DAF0TMB3IC0_F0TG_MB_C_brd_V02_OCP.brd")
		(comment 1 "Grand Teton / footprints 4353-4354 of 8354")
	)
	(layers
		(0 "F.Cu" signal "TOP")
		(4 "In1.Cu" signal "GND")
		(6 "In2.Cu" signal "IN1")
		(8 "In3.Cu" signal "GND1")
		(10 "In4.Cu" signal "IN2")
		(12 "In5.Cu" signal "GND2")
		(14 "In6.Cu" signal "IN3")
		(16 "In7.Cu" signal "GND3")
		(18 "In8.Cu" signal "VCC")
		(20 "In9.Cu" signal "VCC1")
		(22 "In10.Cu" signal "GND4")
		(24 "In11.Cu" signal "IN4")
		(26 "In12.Cu" signal "GND5")
		(28 "In13.Cu" signal "IN5")
		(30 "In14.Cu" signal "GND6")
		(32 "In15.Cu" signal "IN6")
		(34 "In16.Cu" signal "GND7")
		(2 "B.Cu" signal "BOTTOM")
		(9 "F.Adhes" user "F.Adhesive")
		(11 "B.Adhes" user "B.Adhesive")
		(13 "F.Paste" user "Package Geometry/Pastemask Top")
		(15 "B.Paste" user "Package Geometry/Pastemask Bottom")
		(5 "F.SilkS" user "Ref Des/Silkscreen Top")
		(7 "B.SilkS" user "Ref Des/Silkscreen Bottom")
		(1 "F.Mask" user "Board Geometry/Soldermask Top")
		(3 "B.Mask" user "Board Geometry/Soldermask Bottom")
		(17 "Dwgs.User" user "User.Drawings")
		(19 "Cmts.User" user "User.Comments")
		(21 "Eco1.User" user "User.Eco1")
		(23 "Eco2.User" user "User.Eco2")
		(25 "Edge.Cuts" user "Board Geometry/Outline")
		(27 "Margin" user)
		(31 "F.CrtYd" user "Package Geometry/Place Bound Top")
		(29 "B.CrtYd" user "Package Geometry/Place Bound Bottom")
		(35 "F.Fab" user "Ref Des/Assembly Top")
		(33 "B.Fab" user "Ref Des/Assembly Bottom")
	)
	(footprint ""
		(layer "F.Cu")
		(at 15.180818 -410.31287 90)
		(property "Reference" "PU6510"
			(at -3.06324 -7.03707 90)
			(unlocked yes)
			(layer "F.SilkS")
			(effects
				(font
					(size 0.7874 0.5842)
					(thickness 0.1524)
				)
				(justify left)
			)
		)
		(property "Value" ""
			(at 0 0 90)
			(layer "F.Fab")
			(effects
				(font
					(size 1.27 1.27)
				)
			)
		)
		(duplicate_pad_numbers_are_jumpers no)
		(fp_line
			(start 0.1778 -3.2385)
			(end 0.1778 -2.8575)
			(stroke
				(width 0.1524)
				(type default)
			)
			(layer "F.SilkS")
		)
		(fp_line
			(start -1.8034 -2.8702)
			(end -1.8034 -3.6322)
			(stroke
				(width 0.1524)
				(type default)
			)
			(layer "F.SilkS")
		)
		(fp_line
			(start 2.500122 -2.500122)
			(end 2.500122 -2.015998)
			(stroke
				(width 0.1524)
				(type default)
			)
			(layer "F.SilkS")
		)
		(fp_line
			(start 2.015998 -2.500122)
			(end 2.500122 -2.500122)
			(stroke
				(width 0.1524)
				(type default)
			)
			(layer "F.SilkS")
		)
		(fp_line
			(start -2.500122 -2.500122)
			(end -2.015998 -2.500122)
			(stroke
				(width 0.1524)
				(type default)
			)
			(layer "F.SilkS")
		)
		(fp_line
			(start -2.500122 -2.015998)
			(end -2.500122 -2.500122)
			(stroke
				(width 0.1524)
				(type default)
			)
			(layer "F.SilkS")
		)
		(fp_line
			(start 2.8702 -1.778)
			(end 3.6322 -1.778)
			(stroke
				(width 0.1524)
				(type default)
			)
			(layer "F.SilkS")
		)
		(fp_line
			(start -3.2639 -0.1778)
			(end -2.8829 -0.1778)
			(stroke
				(width 0.1524)
				(type default)
			)
			(layer "F.SilkS")
		)
		(fp_line
			(start 2.8829 0.2032)
			(end 3.2639 0.2032)
			(stroke
				(width 0.1524)
				(type default)
			)
			(layer "F.SilkS")
		)
		(fp_line
			(start -3.6576 1.8034)
			(end -2.8956 1.8034)
			(stroke
				(width 0.1524)
				(type default)
			)
			(layer "F.SilkS")
		)
		(fp_line
			(start 2.500122 2.015998)
			(end 2.500122 2.500122)
			(stroke
				(width 0.1524)
				(type default)
			)
			(layer "F.SilkS")
		)
		(fp_line
			(start 2.500122 2.500122)
			(end 2.015998 2.500122)
			(stroke
				(width 0.1524)
				(type default)
			)
			(layer "F.SilkS")
		)
		(fp_line
			(start -2.015998 2.500122)
			(end -2.500122 2.500122)
			(stroke
				(width 0.1524)
				(type default)
			)
			(layer "F.SilkS")
		)
		(fp_line
			(start -2.500122 2.500122)
			(end -2.500122 2.018538)
			(stroke
				(width 0.1524)
				(type default)
			)
			(layer "F.SilkS")
		)
		(fp_line
			(start -0.2032 2.8829)
			(end -0.2032 3.2639)
			(stroke
				(width 0.1524)
				(type default)
			)
			(layer "F.SilkS")
		)
		(fp_line
			(start 1.778 3.6322)
			(end 1.778 2.8702)
			(stroke
				(width 0.1524)
				(type default)
			)
			(layer "F.SilkS")
		)
		(fp_poly
			(pts
				(xy -2.921 -1.800098) (xy -3.504184 -1.508506) (xy -3.504184 -2.09169)
			)
			(stroke
				(width 0)
				(type default)
			)
			(fill yes)
			(layer "F.SilkS")
		)
		(fp_line
			(start 0.1778 -3.2385)
			(end 0.1778 -2.8575)
			(stroke
				(width 0.1)
				(type default)
			)
			(layer "F.Fab")
		)
		(fp_line
			(start -1.8034 -2.8702)
			(end -1.8034 -3.6322)
			(stroke
				(width 0.1)
				(type default)
			)
			(layer "F.Fab")
		)
		(fp_line
			(start 2.500122 -2.500122)
			(end 2.500122 2.500122)
			(stroke
				(width 0.1)
				(type default)
			)
			(layer "F.Fab")
		)
		(fp_line
			(start -2.500122 -2.500122)
			(end 2.500122 -2.500122)
			(stroke
				(width 0.1)
				(type default)
			)
			(layer "F.Fab")
		)
		(fp_line
			(start 2.8702 -1.778)
			(end 3.6322 -1.778)
			(stroke
				(width 0.1)
				(type default)
			)
			(layer "F.Fab")
		)
		(fp_line
			(start -3.2639 -0.1778)
			(end -2.8829 -0.1778)
			(stroke
				(width 0.1)
				(type default)
			)
			(layer "F.Fab")
		)
		(fp_line
			(start 2.8829 0.2032)
			(end 3.2639 0.2032)
			(stroke
				(width 0.1)
				(type default)
			)
			(layer "F.Fab")
		)
		(fp_line
			(start -3.6576 1.8034)
			(end -2.8956 1.8034)
			(stroke
				(width 0.1)
				(type default)
			)
			(layer "F.Fab")
		)
		(fp_line
			(start 2.500122 2.500122)
			(end -2.500122 2.500122)
			(stroke
				(width 0.1)
				(type default)
			)
			(layer "F.Fab")
		)
		(fp_line
			(start -2.500122 2.500122)
			(end -2.500122 -2.500122)
			(stroke
				(width 0.1)
				(type default)
			)
			(layer "F.Fab")
		)
		(fp_line
			(start -0.2032 2.8829)
			(end -0.2032 3.2639)
			(stroke
				(width 0.1)
				(type default)
			)
			(layer "F.Fab")
		)
		(fp_line
			(start 1.778 3.6322)
			(end 1.778 2.8702)
			(stroke
				(width 0.1)
				(type default)
			)
			(layer "F.Fab")
		)
		(fp_poly
			(pts
				(xy -2.921 -1.800098) (xy -3.504184 -1.508506) (xy -3.504184 -2.09169)
			)
			(stroke
				(width 0)
				(type default)
			)
			(fill yes)
			(layer "F.Fab")
		)
		(fp_text user "40"
			(at -1.705356 -3.810762 90)
			(unlocked yes)
			(layer "F.SilkS")
			(effects
				(font
					(size 0.635 0.4064)
					(thickness 0.1524)
				)
				(justify left)
			)
		)
		(fp_text user "31"
			(at 1.29413 -3.732276 90)
			(unlocked yes)
			(layer "F.SilkS")
			(effects
				(font
					(size 0.635 0.4064)
					(thickness 0.1524)
				)
				(justify left)
			)
		)
		(fp_text user "30"
			(at 3.54203 -3.011932 0)
			(unlocked yes)
			(layer "F.SilkS")
			(effects
				(font
					(size 0.635 0.4064)
					(thickness 0.1524)
				)
				(justify left)
			)
		)
		(fp_text user "10"
			(at -2.959608 1.924558 0)
			(unlocked yes)
			(layer "F.SilkS")
			(effects
				(font
					(size 0.635 0.4064)
					(thickness 0.1524)
				)
				(justify left)
			)
		)
		(fp_text user "21"
			(at 2.948178 2.247392 0)
			(unlocked yes)
			(layer "F.SilkS")
			(effects
				(font
					(size 0.635 0.4064)
					(thickness 0.1524)
				)
				(justify left)
			)
		)
		(fp_text user "20"
			(at 1.851406 3.561842 90)
			(unlocked yes)
			(layer "F.SilkS")
			(effects
				(font
					(size 0.635 0.4064)
					(thickness 0.1524)
				)
				(justify left)
			)
		)
		(fp_text user "11"
			(at -3.35407 3.809492 90)
			(unlocked yes)
			(layer "F.SilkS")
			(effects
				(font
					(size 0.635 0.4064)
					(thickness 0.1524)
				)
				(justify left)
			)
		)
		(fp_text user "31"
			(at 1.8542 -3.172968 90)
			(unlocked yes)
			(layer "F.Fab")
			(effects
				(font
					(size 0.635 0.4064)
					(thickness 0.1524)
				)
				(justify left)
			)
		)
		(fp_text user "30"
			(at 3.223768 -3.0988 0)
			(unlocked yes)
			(layer "F.Fab")
			(effects
				(font
					(size 0.635 0.4064)
					(thickness 0.1524)
				)
				(justify left)
			)
		)
		(fp_text user "40"
			(at -3.2004 -3.096768 90)
			(unlocked yes)
			(layer "F.Fab")
			(effects
				(font
					(size 0.635 0.4064)
					(thickness 0.1524)
				)
				(justify left)
			)
		)
		(fp_text user "21"
			(at 3.274568 1.8796 0)
			(unlocked yes)
			(layer "F.Fab")
			(effects
				(font
					(size 0.635 0.4064)
					(thickness 0.1524)
				)
				(justify left)
			)
		)
		(fp_text user "10"
			(at -3.253232 2.1336 0)
			(unlocked yes)
			(layer "F.Fab")
			(effects
				(font
					(size 0.635 0.4064)
					(thickness 0.1524)
				)
				(justify left)
			)
		)
		(fp_text user "20"
			(at 2.0828 3.253232 90)
			(unlocked yes)
			(layer "F.Fab")
			(effects
				(font
					(size 0.635 0.4064)
					(thickness 0.1524)
				)
				(justify left)
			)
		)
		(fp_text user "11"
			(at -2.8702 3.278632 90)
			(unlocked yes)
			(layer "F.Fab")
			(effects
				(font
					(size 0.635 0.4064)
					(thickness 0.1524)
				)
				(justify left)
			)
		)
		(pad "1" smd rect
			(at -2.400046 -1.800098)
			(size 0.1778 0.6096)
			(layers "F.Cu" "F.Mask" "F.Paste")
			(net "NC_P0V9_RETIMER_CPU1_PWM8")
		)
		(pad "2" smd rect
			(at -2.400046 -1.400048)
			(size 0.1778 0.6096)
			(layers "F.Cu" "F.Mask" "F.Paste")
			(net "NC_P0V9_RETIMER_CPU1_PWM7")
		)
		(pad "3" smd rect
			(at -2.400046 -0.999998)
			(size 0.1778 0.6096)
			(layers "F.Cu" "F.Mask" "F.Paste")
			(net "NC_P0V9_RETIMER_CPU1_PWM6")
		)
		(pad "4" smd rect
			(at -2.400046 -0.599948)
			(size 0.1778 0.6096)
			(layers "F.Cu" "F.Mask" "F.Paste")
			(net "NC_P0V9_RETIMER_CPU1_PWM5")
		)
		(pad "5" smd rect
			(at -2.400046 -0.199898)
			(size 0.1778 0.6096)
			(layers "F.Cu" "F.Mask" "F.Paste")
			(net "NC_P0V9_RETIMER_CPU1_PWM4")
		)
		(pad "6" smd rect
			(at -2.400046 0.199898)
			(size 0.1778 0.6096)
			(layers "F.Cu" "F.Mask" "F.Paste")
			(net "NC_P0V9_RETIMER_CPU1_PWM3")
		)
		(pad "7" smd rect
			(at -2.400046 0.599948)
			(size 0.1778 0.6096)
			(layers "F.Cu" "F.Mask" "F.Paste")
			(net "P0V9_RETIMER_CPU1_PWM2")
		)
		(pad "8" smd rect
			(at -2.400046 0.999998)
			(size 0.1778 0.6096)
			(layers "F.Cu" "F.Mask" "F.Paste")
			(net "P0V9_RETIMER_CPU1_PWM1")
		)
		(pad "9" smd rect
			(at -2.400046 1.400048)
			(size 0.1778 0.6096)
			(layers "F.Cu" "F.Mask" "F.Paste")
			(net "P0V9_RETIMER_CPU1_PMSDA_R")
		)
		(pad "10" smd rect
			(at -2.400046 1.800098)
			(size 0.1778 0.6096)
			(layers "F.Cu" "F.Mask" "F.Paste")
			(net "P0V9_RETIMER_CPU1_PMSCL_R")
		)
		(pad "11" smd rect
			(at -1.800098 2.400046 90)
			(size 0.1778 0.6096)
			(layers "F.Cu" "F.Mask" "F.Paste")
			(net "TP_P0V9_RETIMER_CPU1_PMALERT")
		)
		(pad "12" smd rect
			(at -1.400048 2.400046 90)
			(size 0.1778 0.6096)
			(layers "F.Cu" "F.Mask" "F.Paste")
			(net "PWRGD_P0V9_RETIMER_CPU1_R")
		)
		(pad "13" smd rect
			(at -0.999998 2.400046 90)
			(size 0.1778 0.6096)
			(layers "F.Cu" "F.Mask" "F.Paste")
			(net "P0V9_RETIMER_CPU1_EN0_R")
		)
		(pad "14" smd rect
			(at -0.599948 2.400046 90)
			(size 0.1778 0.6096)
			(layers "F.Cu" "F.Mask" "F.Paste")
			(net "P0V9_RETIMER_CPU1_VRHOT")
		)
		(pad "15" smd rect
			(at -0.199898 2.400046 90)
			(size 0.1778 0.6096)
			(layers "F.Cu" "F.Mask" "F.Paste")
			(net "P0V9_RETIMER_CPU1_INALERT")
		)
		(pad "16" smd rect
			(at 0.199898 2.400046 90)
			(size 0.1778 0.6096)
			(layers "F.Cu" "F.Mask" "F.Paste")
			(net "NC_P0V9_RETIMER_CPU1_PG1")
		)
		(pad "17" smd rect
			(at 0.599948 2.400046 90)
			(size 0.1778 0.6096)
			(layers "F.Cu" "F.Mask" "F.Paste")
			(net "P0V9_RETIMER_CPU1_SVID_CLK")
		)
		(pad "18" smd rect
			(at 0.999998 2.400046 90)
			(size 0.1778 0.6096)
			(layers "F.Cu" "F.Mask" "F.Paste")
			(net "P0V9_RETIMER_CPU1_SVID_SDA")
		)
		(pad "19" smd rect
			(at 1.400048 2.400046 90)
			(size 0.1778 0.6096)
			(layers "F.Cu" "F.Mask" "F.Paste")
			(net "TP_P0V9_RETIMER_CPU1_SVID_ALERT_N")
		)
		(pad "20" smd rect
			(at 1.800098 2.400046 90)
			(size 0.1778 0.6096)
			(layers "F.Cu" "F.Mask" "F.Paste")
			(net "P0V9_RETIMER_CPU1_EN1_R")
		)
		(pad "21" smd rect
			(at 2.400046 1.800098)
			(size 0.1778 0.6096)
			(layers "F.Cu" "F.Mask" "F.Paste")
			(net "P0V9_RETIMER_CPU1_SENSE_R_P")
		)
		(pad "22" smd rect
			(at 2.400046 1.400048)
			(size 0.1778 0.6096)
			(layers "F.Cu" "F.Mask" "F.Paste")
			(net "P0V9_RETIMER_CPU1_SENSE_SH_N")
		)
		(pad "23" smd rect
			(at 2.400046 0.999998)
			(size 0.1778 0.6096)
			(layers "F.Cu" "F.Mask" "F.Paste")
			(net "P0V9_RETIMER_CPU1_IMON1")
		)
		(pad "24" smd rect
			(at 2.400046 0.599948)
			(size 0.1778 0.6096)
			(layers "F.Cu" "F.Mask" "F.Paste")
			(net "P0V9_RETIMER_CPU1_IMON2")
		)
		(pad "25" smd rect
			(at 2.400046 0.199898)
			(size 0.1778 0.6096)
			(layers "F.Cu" "F.Mask" "F.Paste")
			(net "NC_P0V9_RETIMER_CPU1_IMON3")
		)
		(pad "26" smd rect
			(at 2.400046 -0.199898)
			(size 0.1778 0.6096)
			(layers "F.Cu" "F.Mask" "F.Paste")
			(net "NC_P0V9_RETIMER_CPU1_IMON4")
		)
		(pad "27" smd rect
			(at 2.400046 -0.599948)
			(size 0.1778 0.6096)
			(layers "F.Cu" "F.Mask" "F.Paste")
			(net "NC_P0V9_RETIMER_CPU1_IMON5")
		)
		(pad "28" smd rect
			(at 2.400046 -0.999998)
			(size 0.1778 0.6096)
			(layers "F.Cu" "F.Mask" "F.Paste")
			(net "NC_P0V9_RETIMER_CPU1_IMON6")
		)
		(pad "29" smd rect
			(at 2.400046 -1.400048)
			(size 0.1778 0.6096)
			(layers "F.Cu" "F.Mask" "F.Paste")
			(net "NC_P0V9_RETIMER_CPU1_IMON7")
		)
		(pad "30" smd rect
			(at 2.400046 -1.800098)
			(size 0.1778 0.6096)
			(layers "F.Cu" "F.Mask" "F.Paste")
			(net "NC_P0V9_RETIMER_CPU1_IMON8")
		)
		(pad "31" smd rect
			(at 1.800098 -2.400046 90)
			(size 0.1778 0.6096)
			(layers "F.Cu" "F.Mask" "F.Paste")
			(net "GND")
		)
		(pad "32" smd rect
			(at 1.400048 -2.400046 90)
			(size 0.1778 0.6096)
			(layers "F.Cu" "F.Mask" "F.Paste")
			(net "GND")
		)
		(pad "33" smd rect
			(at 0.999998 -2.400046 90)
			(size 0.1778 0.6096)
			(layers "F.Cu" "F.Mask" "F.Paste")
			(net "P0V9_RETIMER_CPU1_CFP")
		)
		(pad "34" smd rect
			(at 0.599948 -2.400046 90)
			(size 0.1778 0.6096)
			(layers "F.Cu" "F.Mask" "F.Paste")
			(net "P0V9_RETIMER_CPU1_ADDR")
		)
		(pad "35" smd rect
			(at 0.199898 -2.400046 90)
			(size 0.1778 0.6096)
			(layers "F.Cu" "F.Mask" "F.Paste")
			(net "P0V9_RETIMER_CPU1_TEMP0")
		)
		(pad "36" smd rect
			(at -0.199898 -2.400046 90)
			(size 0.1778 0.6096)
			(layers "F.Cu" "F.Mask" "F.Paste")
			(net "P0V9_RETIMER_CPU1_TEMP1_R")
		)
		(pad "37" smd rect
			(at -0.599948 -2.400046 90)
			(size 0.1778 0.6096)
			(layers "F.Cu" "F.Mask" "F.Paste")
			(net "P0V9_RETIMER_CPU1_VMON")
		)
		(pad "38" smd rect
			(at -0.999998 -2.400046 90)
			(size 0.1778 0.6096)
			(layers "F.Cu" "F.Mask" "F.Paste")
			(net "P0V9_RETIMER_CPU1_VINSEN")
		)
		(pad "39" smd rect
			(at -1.400048 -2.400046 90)
			(size 0.1778 0.6096)
			(layers "F.Cu" "F.Mask" "F.Paste")
			(net "P0V9_RETIMER_CPU1_VCC")
		)
		(pad "40" smd rect
			(at -1.800098 -2.400046 90)
			(size 0.1778 0.6096)
			(layers "F.Cu" "F.Mask" "F.Paste")
			(net "PV09_RETIMER_CPU1_VCCS")
		)
		(pad "TH" smd rect
			(at 0 0 90)
			(size 3.6576 3.6576)
			(layers "F.Cu" "F.Mask" "F.Paste")
			(net "GND")
		)
		(zone
			(layer "F.Cu")
			(hatch none 0.5)
			(connect_pads
				(clearance 0)
			)
			(min_thickness 0.25)
			(keepout
				(tracks not_allowed)
				(vias allowed)
				(pads allowed)
				(copperpour not_allowed)
				(footprints allowed)
			)
			(placement
				(enabled no)
				(sheetname "")
			)
			(fill
				(thermal_gap 0.5)
				(thermal_bridge_width 0.5)
				(island_removal_mode 0)
			)
			(polygon
				(pts
					(xy 13.148818 -408.28087) (xy 13.148818 -412.34487) (xy 17.212818 -412.34487) (xy 17.212818 -408.28087)
					(xy 13.326618 -408.28087) (xy 13.326618 -408.43327) (xy 17.060418 -408.43327) (xy 17.060418 -412.19247)
					(xy 13.301218 -412.19247) (xy 13.301218 -408.28087)
				)
			)
		)
	)
	(footprint ""
		(layer "F.Cu")
		(at 324.529958 -193.925952 -90)
		(property "Reference" "R418"
			(at 0 0 270)
			(layer "F.SilkS")
			(hide yes)
			(effects
				(font
					(size 1.27 1.27)
				)
			)
		)
		(property "Value" ""
			(at 0 0 270)
			(layer "F.Fab")
			(effects
				(font
					(size 1.27 1.27)
				)
			)
		)
		(duplicate_pad_numbers_are_jumpers no)
		(fp_line
			(start -0.7874 0.4064)
			(end -0.7874 -0.4064)
			(stroke
				(width 0.1524)
				(type default)
			)
			(layer "F.SilkS")
		)
		(fp_line
			(start 0.7874 0.4064)
			(end -0.7874 0.4064)
			(stroke
				(width 0.1524)
				(type default)
			)
			(layer "F.SilkS")
		)
		(fp_line
			(start -0.7874 -0.4064)
			(end 0.7874 -0.4064)
			(stroke
				(width 0.1524)
				(type default)
			)
			(layer "F.SilkS")
		)
		(fp_line
			(start 0.7874 -0.4064)
			(end 0.7874 0.4064)
			(stroke
				(width 0.1524)
				(type default)
			)
			(layer "F.SilkS")
		)
		(fp_line
			(start -0.67945 0.3048)
			(end -0.67945 -0.305054)
			(stroke
				(width 0.1)
				(type default)
			)
			(layer "F.Fab")
		)
		(fp_line
			(start -0.12065 0.3048)
			(end -0.67945 0.3048)
			(stroke
				(width 0.1)
				(type default)
			)
			(layer "F.Fab")
		)
		(fp_line
			(start 0.120396 0.3048)
			(end 0.120396 0.2794)
			(stroke
				(width 0.1)
				(type default)
			)
			(layer "F.Fab")
		)
		(fp_line
			(start 0.67945 0.3048)
			(end 0.120396 0.3048)
			(stroke
				(width 0.1)
				(type default)
			)
			(layer "F.Fab")
		)
		(fp_line
			(start -0.12065 0.2794)
			(end -0.12065 0.3048)
			(stroke
				(width 0.1)
				(type default)
			)
			(layer "F.Fab")
		)
		(fp_line
			(start 0.120396 0.2794)
			(end -0.12065 0.2794)
			(stroke
				(width 0.1)
				(type default)
			)
			(layer "F.Fab")
		)
		(fp_line
			(start -0.12065 -0.2794)
			(end 0.12065 -0.2794)
			(stroke
				(width 0.1)
				(type default)
			)
			(layer "F.Fab")
		)
		(fp_line
			(start 0.12065 -0.2794)
			(end 0.12065 -0.3048)
			(stroke
				(width 0.1)
				(type default)
			)
			(layer "F.Fab")
		)
		(fp_line
			(start 0.12065 -0.3048)
			(end 0.67945 -0.3048)
			(stroke
				(width 0.1)
				(type default)
			)
			(layer "F.Fab")
		)
		(fp_line
			(start 0.67945 -0.3048)
			(end 0.67945 0.3048)
			(stroke
				(width 0.1)
				(type default)
			)
			(layer "F.Fab")
		)
		(fp_line
			(start -0.67945 -0.305054)
			(end -0.12065 -0.305054)
			(stroke
				(width 0.1)
				(type default)
			)
			(layer "F.Fab")
		)
		(fp_line
			(start -0.12065 -0.305054)
			(end -0.12065 -0.2794)
			(stroke
				(width 0.1)
				(type default)
			)
			(layer "F.Fab")
		)
		(pad "1" smd circle
			(at -0.40005 0 270)
			(size 0 0)
			(layers "F.Cu" "F.Mask" "F.Paste")
			(net "APML_CPU0_ALERT_N")
		)
		(pad "2" smd circle
			(at 0.40005 0 270)
			(size 0 0)
			(layers "F.Cu" "F.Mask" "F.Paste")
			(net "PVDD18_S5_P0")
		)
	)
)
